(kicad_pcb
	(version 20260206)
	(generator "pcbnew")
	(generator_version "10.0")
	(general
		(thickness 1.21888)
		(legacy_teardrops no)
	)
	(paper "A4")
	(title_block
		(title "timecard-v7 — TimeCard-DC-V7_EXP.PcbDoc")
		(comment 1 "Time Appliance Project (Time Card) / footprints 118-120 of 160")
	)
	(layers
		(0 "F.Cu" signal "TOP")
		(4 "In1.Cu" signal "SGND")
		(6 "In2.Cu" signal "IN1")
		(8 "In3.Cu" signal "IN2")
		(10 "In4.Cu" signal "SGND1")
		(2 "B.Cu" signal "BOTTOM")
		(9 "F.Adhes" user "F.Adhesive")
		(11 "B.Adhes" user "B.Adhesive")
		(13 "F.Paste" user "Top Paste")
		(15 "B.Paste" user "Bottom Paste")
		(5 "F.SilkS" user "Top Overlay")
		(7 "B.SilkS" user "Bottom Overlay")
		(1 "F.Mask" user "Top Solder")
		(3 "B.Mask" user "Bottom Solder")
		(17 "Dwgs.User" user "User.Drawings")
		(19 "Cmts.User" user "User.Comments")
		(21 "Eco1.User" user "User.Eco1")
		(23 "Eco2.User" user "User.Eco2")
		(25 "Edge.Cuts" user)
		(27 "Margin" user)
		(31 "F.CrtYd" user "Top Courtyard")
		(29 "B.CrtYd" user "Bottom Courtyard")
		(35 "F.Fab" user "Top Component Center")
		(33 "B.Fab" user "Bottom Component Center")
	)
	(footprint "FPGA_CONN:SingleFPGAConn"
		(layer "F.Cu")
		(at 182.5759 133.49995 90)
		(property "Reference" "J37"
			(at -0.368955 -23.428198 90)
			(unlocked yes)
			(layer "F.SilkS")
			(effects
				(font
					(size 1.524 1.524)
					(thickness 0.254)
				)
			)
		)
		(property "Value" "Single FPGA Conn"
			(at 9.27992 3.521202 90)
			(unlocked yes)
			(layer "F.SilkS")
			(hide yes)
			(effects
				(font
					(size 1.524 1.524)
					(thickness 0.254)
				)
			)
		)
		(sheetname "FPGA")
		(sheetfile "FPGA.kicad_sch")
		(duplicate_pad_numbers_are_jumpers no)
		(fp_line
			(start 1.40004 -21.2499)
			(end 1.40004 -20.69999)
			(stroke
				(width 0.15011)
				(type solid)
			)
			(layer "F.SilkS")
		)
		(fp_line
			(start -1.40005 -21.2499)
			(end 1.40004 -21.2499)
			(stroke
				(width 0.15011)
				(type solid)
			)
			(layer "F.SilkS")
		)
		(fp_line
			(start -1.40005 -21.2499)
			(end -1.40005 -20.69999)
			(stroke
				(width 0.15011)
				(type solid)
			)
			(layer "F.SilkS")
		)
		(fp_line
			(start 1.99999 -20.69999)
			(end 1.99999 -20.03298)
			(stroke
				(width 0.15011)
				(type solid)
			)
			(layer "F.SilkS")
		)
		(fp_line
			(start 1.40004 -20.69999)
			(end 1.99999 -20.69999)
			(stroke
				(width 0.15011)
				(type solid)
			)
			(layer "F.SilkS")
		)
		(fp_line
			(start -2 -20.69999)
			(end -1.40005 -20.69999)
			(stroke
				(width 0.15011)
				(type solid)
			)
			(layer "F.SilkS")
		)
		(fp_line
			(start -2 -20.69999)
			(end -2 -20.03298)
			(stroke
				(width 0.15011)
				(type solid)
			)
			(layer "F.SilkS")
		)
		(fp_line
			(start 1.99999 0.03302)
			(end 1.99999 0.70002)
			(stroke
				(width 0.15011)
				(type solid)
			)
			(layer "F.SilkS")
		)
		(fp_line
			(start -2 0.03302)
			(end -2 0.70002)
			(stroke
				(width 0.15011)
				(type solid)
			)
			(layer "F.SilkS")
		)
		(fp_line
			(start 1.40004 0.70002)
			(end 1.99999 0.70002)
			(stroke
				(width 0.15011)
				(type solid)
			)
			(layer "F.SilkS")
		)
		(fp_line
			(start 1.40004 0.70002)
			(end 1.40004 1.24993)
			(stroke
				(width 0.15011)
				(type solid)
			)
			(layer "F.SilkS")
		)
		(fp_line
			(start -1.40005 0.70002)
			(end -1.40005 1.24993)
			(stroke
				(width 0.15011)
				(type solid)
			)
			(layer "F.SilkS")
		)
		(fp_line
			(start -2 0.70002)
			(end -1.40005 0.70002)
			(stroke
				(width 0.15011)
				(type solid)
			)
			(layer "F.SilkS")
		)
		(fp_line
			(start -1.40005 1.24993)
			(end 1.40004 1.24993)
			(stroke
				(width 0.15011)
				(type solid)
			)
			(layer "F.SilkS")
		)
		(fp_circle
			(center 3.5052 -0.22454)
			(end 3.70535 -0.22454)
			(stroke
				(width 0.40005)
				(type solid)
			)
			(fill no)
			(layer "F.SilkS")
		)
		(pad "1" smd rect
			(at 2.02488 -0.24994 90)
			(size 1.54991 0.24994)
			(layers "F.Cu" "F.Mask" "F.Paste")
		)
		(pad "2" smd rect
			(at -2.02489 -0.24994 90)
			(size 1.54991 0.24994)
			(layers "F.Cu" "F.Mask" "F.Paste")
		)
		(pad "3" smd rect
			(at 2.02488 -0.75006 90)
			(size 1.54991 0.24994)
			(layers "F.Cu" "F.Mask" "F.Paste")
		)
		(pad "4" smd rect
			(at -2.02489 -0.75006 90)
			(size 1.54991 0.24994)
			(layers "F.Cu" "F.Mask" "F.Paste")
		)
		(pad "5" smd rect
			(at 2.02488 -1.24994 90)
			(size 1.54991 0.24994)
			(layers "F.Cu" "F.Mask" "F.Paste")
		)
		(pad "6" smd rect
			(at -2.02489 -1.24994 90)
			(size 1.54991 0.24994)
			(layers "F.Cu" "F.Mask" "F.Paste")
		)
		(pad "7" smd rect
			(at 2.02488 -1.75006 90)
			(size 1.54991 0.24994)
			(layers "F.Cu" "F.Mask" "F.Paste")
		)
		(pad "8" smd rect
			(at -2.02489 -1.75006 90)
			(size 1.54991 0.24994)
			(layers "F.Cu" "F.Mask" "F.Paste")
		)
		(pad "9" smd rect
			(at 2.02488 -2.24993 90)
			(size 1.54991 0.24994)
			(layers "F.Cu" "F.Mask" "F.Paste")
			(net "GND")
		)
		(pad "10" smd rect
			(at -2.02489 -2.24993 90)
			(size 1.54991 0.24994)
			(layers "F.Cu" "F.Mask" "F.Paste")
			(net "GND")
		)
		(pad "11" smd rect
			(at 2.02488 -2.75006 90)
			(size 1.54991 0.24994)
			(layers "F.Cu" "F.Mask" "F.Paste")
		)
		(pad "12" smd rect
			(at -2.02489 -2.75006 90)
			(size 1.54991 0.24994)
			(layers "F.Cu" "F.Mask" "F.Paste")
			(net "PCIE_TX2_P")
		)
		(pad "13" smd rect
			(at 2.02488 -3.24993 90)
			(size 1.54991 0.24994)
			(layers "F.Cu" "F.Mask" "F.Paste")
		)
		(pad "14" smd rect
			(at -2.02489 -3.24993 90)
			(size 1.54991 0.24994)
			(layers "F.Cu" "F.Mask" "F.Paste")
			(net "PCIE_TX2_N")
		)
		(pad "15" smd rect
			(at 2.02488 -3.75006 90)
			(size 1.54991 0.24994)
			(layers "F.Cu" "F.Mask" "F.Paste")
			(net "GND")
		)
		(pad "16" smd rect
			(at -2.02489 -3.75006 90)
			(size 1.54991 0.24994)
			(layers "F.Cu" "F.Mask" "F.Paste")
		)
		(pad "17" smd rect
			(at 2.02488 -4.24993 90)
			(size 1.54991 0.24994)
			(layers "F.Cu" "F.Mask" "F.Paste")
			(net "PCIE_TX3_P")
		)
		(pad "18" smd rect
			(at -2.02489 -4.24993 90)
			(size 1.54991 0.24994)
			(layers "F.Cu" "F.Mask" "F.Paste")
			(net "PCIE_RX2_P")
		)
		(pad "19" smd rect
			(at 2.02488 -4.75006 90)
			(size 1.54991 0.24994)
			(layers "F.Cu" "F.Mask" "F.Paste")
			(net "PCIE_TX3_N")
		)
		(pad "20" smd rect
			(at -2.02489 -4.75006 90)
			(size 1.54991 0.24994)
			(layers "F.Cu" "F.Mask" "F.Paste")
			(net "PCIE_RX2_N")
		)
		(pad "21" smd rect
			(at 2.02488 -5.24993 90)
			(size 1.54991 0.24994)
			(layers "F.Cu" "F.Mask" "F.Paste")
			(net "GND")
		)
		(pad "22" smd rect
			(at -2.02489 -5.24993 90)
			(size 1.54991 0.24994)
			(layers "F.Cu" "F.Mask" "F.Paste")
		)
		(pad "23" smd rect
			(at 2.02488 -5.75005 90)
			(size 1.54991 0.24994)
			(layers "F.Cu" "F.Mask" "F.Paste")
			(net "PCIE_RX3_P")
		)
		(pad "24" smd rect
			(at -2.02489 -5.75005 90)
			(size 1.54991 0.24994)
			(layers "F.Cu" "F.Mask" "F.Paste")
			(net "PCIE_TX1_P")
		)
		(pad "25" smd rect
			(at 2.02488 -6.24993 90)
			(size 1.54991 0.24994)
			(layers "F.Cu" "F.Mask" "F.Paste")
			(net "PCIE_RX3_N")
		)
		(pad "26" smd rect
			(at -2.02489 -6.24993 90)
			(size 1.54991 0.24994)
			(layers "F.Cu" "F.Mask" "F.Paste")
			(net "PCIE_TX1_N")
		)
		(pad "27" smd rect
			(at 2.02488 -6.75005 90)
			(size 1.54991 0.24994)
			(layers "F.Cu" "F.Mask" "F.Paste")
			(net "GND")
		)
		(pad "28" smd rect
			(at -2.02489 -6.75005 90)
			(size 1.54991 0.24994)
			(layers "F.Cu" "F.Mask" "F.Paste")
		)
		(pad "29" smd rect
			(at 2.02488 -7.24992 90)
			(size 1.54991 0.24994)
			(layers "F.Cu" "F.Mask" "F.Paste")
			(net "PCIE_TX0_P")
		)
		(pad "30" smd rect
			(at -2.02489 -7.24992 90)
			(size 1.54991 0.24994)
			(layers "F.Cu" "F.Mask" "F.Paste")
			(net "PCIE_RX1_P")
		)
		(pad "31" smd rect
			(at 2.02488 -7.75005 90)
			(size 1.54991 0.24994)
			(layers "F.Cu" "F.Mask" "F.Paste")
			(net "PCIE_TX0_N")
		)
		(pad "32" smd rect
			(at -2.02489 -7.75005 90)
			(size 1.54991 0.24994)
			(layers "F.Cu" "F.Mask" "F.Paste")
			(net "PCIE_RX1_N")
		)
		(pad "33" smd rect
			(at 2.02488 -8.24992 90)
			(size 1.54991 0.24994)
			(layers "F.Cu" "F.Mask" "F.Paste")
			(net "GND")
		)
		(pad "34" smd rect
			(at -2.02489 -8.24992 90)
			(size 1.54991 0.24994)
			(layers "F.Cu" "F.Mask" "F.Paste")
		)
		(pad "35" smd rect
			(at 2.02488 -8.75005 90)
			(size 1.54991 0.24994)
			(layers "F.Cu" "F.Mask" "F.Paste")
			(net "PCIE_RX0_P")
		)
		(pad "36" smd rect
			(at -2.02489 -8.75005 90)
			(size 1.54991 0.24994)
			(layers "F.Cu" "F.Mask" "F.Paste")
			(net "PCIE_CLK_P")
		)
		(pad "37" smd rect
			(at 2.02488 -9.24992 90)
			(size 1.54991 0.24994)
			(layers "F.Cu" "F.Mask" "F.Paste")
			(net "PCIE_RX0_N")
		)
		(pad "38" smd rect
			(at -2.02489 -9.24992 90)
			(size 1.54991 0.24994)
			(layers "F.Cu" "F.Mask" "F.Paste")
			(net "PCIE_CLK_N")
		)
		(pad "39" smd rect
			(at 2.02488 -9.75005 90)
			(size 1.54991 0.24994)
			(layers "F.Cu" "F.Mask" "F.Paste")
			(net "GND")
		)
		(pad "40" smd rect
			(at -2.02489 -9.75005 90)
			(size 1.54991 0.24994)
			(layers "F.Cu" "F.Mask" "F.Paste")
			(net "GND")
		)
		(pad "41" smd rect
			(at 2.02488 -10.24992 90)
			(size 1.54991 0.24994)
			(layers "F.Cu" "F.Mask" "F.Paste")
		)
		(pad "42" smd rect
			(at -2.02489 -10.24992 90)
			(size 1.54991 0.24994)
			(layers "F.Cu" "F.Mask" "F.Paste")
		)
		(pad "43" smd rect
			(at 2.02488 -10.75004 90)
			(size 1.54991 0.24994)
			(layers "F.Cu" "F.Mask" "F.Paste")
		)
		(pad "44" smd rect
			(at -2.02489 -10.75004 90)
			(size 1.54991 0.24994)
			(layers "F.Cu" "F.Mask" "F.Paste")
		)
		(pad "45" smd rect
			(at 2.02488 -11.24992 90)
			(size 1.54991 0.24994)
			(layers "F.Cu" "F.Mask" "F.Paste")
		)
		(pad "46" smd rect
			(at -2.02489 -11.24992 90)
			(size 1.54991 0.24994)
			(layers "F.Cu" "F.Mask" "F.Paste")
		)
		(pad "47" smd rect
			(at 2.02488 -11.75004 90)
			(size 1.54991 0.24994)
			(layers "F.Cu" "F.Mask" "F.Paste")
		)
		(pad "48" smd rect
			(at -2.02489 -11.75004 90)
			(size 1.54991 0.24994)
			(layers "F.Cu" "F.Mask" "F.Paste")
		)
		(pad "49" smd rect
			(at 2.02488 -12.24991 90)
			(size 1.54991 0.24994)
			(layers "F.Cu" "F.Mask" "F.Paste")
			(net "GND")
		)
		(pad "50" smd rect
			(at -2.02489 -12.24991 90)
			(size 1.54991 0.24994)
			(layers "F.Cu" "F.Mask" "F.Paste")
			(net "GND")
		)
		(pad "51" smd rect
			(at 2.02488 -12.75004 90)
			(size 1.54991 0.24994)
			(layers "F.Cu" "F.Mask" "F.Paste")
		)
		(pad "52" smd rect
			(at -2.02489 -12.75004 90)
			(size 1.54991 0.24994)
			(layers "F.Cu" "F.Mask" "F.Paste")
		)
		(pad "53" smd rect
			(at 2.02488 -13.24991 90)
			(size 1.54991 0.24994)
			(layers "F.Cu" "F.Mask" "F.Paste")
		)
		(pad "54" smd rect
			(at -2.02489 -13.24991 90)
			(size 1.54991 0.24994)
			(layers "F.Cu" "F.Mask" "F.Paste")
		)
		(pad "55" smd rect
			(at 2.02488 -13.75004 90)
			(size 1.54991 0.24994)
			(layers "F.Cu" "F.Mask" "F.Paste")
		)
		(pad "56" smd rect
			(at -2.02489 -13.75004 90)
			(size 1.54991 0.24994)
			(layers "F.Cu" "F.Mask" "F.Paste")
		)
		(pad "57" smd rect
			(at 2.02488 -14.24991 90)
			(size 1.54991 0.24994)
			(layers "F.Cu" "F.Mask" "F.Paste")
		)
		(pad "58" smd rect
			(at -2.02489 -14.24991 90)
			(size 1.54991 0.24994)
			(layers "F.Cu" "F.Mask" "F.Paste")
		)
		(pad "59" smd rect
			(at 2.02488 -14.75004 90)
			(size 1.54991 0.24994)
			(layers "F.Cu" "F.Mask" "F.Paste")
			(net "GND")
		)
		(pad "60" smd rect
			(at -2.02489 -14.75004 90)
			(size 1.54991 0.24994)
			(layers "F.Cu" "F.Mask" "F.Paste")
			(net "GND")
		)
		(pad "61" smd rect
			(at 2.02488 -15.24991 90)
			(size 1.54991 0.24994)
			(layers "F.Cu" "F.Mask" "F.Paste")
		)
		(pad "62" smd rect
			(at -2.02489 -15.24991 90)
			(size 1.54991 0.24994)
			(layers "F.Cu" "F.Mask" "F.Paste")
		)
		(pad "63" smd rect
			(at 2.02488 -15.75003 90)
			(size 1.54991 0.24994)
			(layers "F.Cu" "F.Mask" "F.Paste")
		)
		(pad "64" smd rect
			(at -2.02489 -15.75003 90)
			(size 1.54991 0.24994)
			(layers "F.Cu" "F.Mask" "F.Paste")
		)
		(pad "65" smd rect
			(at 2.02488 -16.24991 90)
			(size 1.54991 0.24994)
			(layers "F.Cu" "F.Mask" "F.Paste")
		)
		(pad "66" smd rect
			(at -2.02489 -16.24991 90)
			(size 1.54991 0.24994)
			(layers "F.Cu" "F.Mask" "F.Paste")
		)
		(pad "67" smd rect
			(at 2.02488 -16.75003 90)
			(size 1.54991 0.24994)
			(layers "F.Cu" "F.Mask" "F.Paste")
		)
		(pad "68" smd rect
			(at -2.02489 -16.75003 90)
			(size 1.54991 0.24994)
			(layers "F.Cu" "F.Mask" "F.Paste")
		)
		(pad "69" smd rect
			(at 2.02488 -17.2499 90)
			(size 1.54991 0.24994)
			(layers "F.Cu" "F.Mask" "F.Paste")
			(net "GND")
		)
		(pad "70" smd rect
			(at -2.02489 -17.2499 90)
			(size 1.54991 0.24994)
			(layers "F.Cu" "F.Mask" "F.Paste")
			(net "GND")
		)
		(pad "71" smd rect
			(at 2.02488 -17.75003 90)
			(size 1.54991 0.24994)
			(layers "F.Cu" "F.Mask" "F.Paste")
		)
		(pad "72" smd rect
			(at -2.02489 -17.75003 90)
			(size 1.54991 0.24994)
			(layers "F.Cu" "F.Mask" "F.Paste")
		)
		(pad "73" smd rect
			(at 2.02488 -18.2499 90)
			(size 1.54991 0.24994)
			(layers "F.Cu" "F.Mask" "F.Paste")
		)
		(pad "74" smd rect
			(at -2.02489 -18.2499 90)
			(size 1.54991 0.24994)
			(layers "F.Cu" "F.Mask" "F.Paste")
		)
		(pad "75" smd rect
			(at 2.02488 -18.75003 90)
			(size 1.54991 0.24994)
			(layers "F.Cu" "F.Mask" "F.Paste")
		)
		(pad "76" smd rect
			(at -2.02489 -18.75003 90)
			(size 1.54991 0.24994)
			(layers "F.Cu" "F.Mask" "F.Paste")
		)
		(pad "77" smd rect
			(at 2.02488 -19.2499 90)
			(size 1.54991 0.24994)
			(layers "F.Cu" "F.Mask" "F.Paste")
		)
		(pad "78" smd rect
			(at -2.02489 -19.2499 90)
			(size 1.54991 0.24994)
			(layers "F.Cu" "F.Mask" "F.Paste")
		)
		(pad "79" smd rect
			(at 2.02488 -19.75003 90)
			(size 1.54991 0.24994)
			(layers "F.Cu" "F.Mask" "F.Paste")
		)
		(pad "80" smd rect
			(at -2.02489 -19.75003 90)
			(size 1.54991 0.24994)
			(layers "F.Cu" "F.Mask" "F.Paste")
		)
		(pad "81" smd rect
			(at 0.01135 1.17626 90)
			(size 1.70002 1.35001)
			(layers "F.Cu" "F.Mask" "F.Paste")
		)
		(pad "82" thru_hole circle
			(at 0 0 90)
			(size 0.55016 0.55016)
			(drill 0.55016)
			(layers "*.Cu" "*.Mask")
			(remove_unused_layers no)
			(thermal_bridge_angle 90)
		)
		(pad "83" thru_hole circle
			(at 0 -19.99996 90)
			(size 0.55016 0.55016)
			(drill 0.55016)
			(layers "*.Cu" "*.Mask")
			(remove_unused_layers no)
			(thermal_bridge_angle 90)
		)
		(pad "84" smd rect
			(at 0.01135 -21.17374 90)
			(size 1.70002 1.35001)
			(layers "F.Cu" "F.Mask" "F.Paste")
		)
	)
	(footprint "Vault:CAPC1608X87X45ML20T05"
		(layer "F.Cu")
		(at 227.5761 67.8286)
		(property "Reference" "C37"
			(at -2.9714 0.276921 0)
			(unlocked yes)
			(layer "F.SilkS")
			(effects
				(font
					(size 0.762 0.762)
					(thickness 0.2286)
				)
			)
		)
		(property "Value" "0.1uF"
			(at 2.09443 2.657602 0)
			(unlocked yes)
			(layer "F.SilkS")
			(hide yes)
			(effects
				(font
					(size 1.524 1.524)
					(thickness 0.254)
				)
			)
		)
		(sheetname "GPS_IMU_SENSORS")
		(sheetfile "GPS_IMU_SENSORS.kicad_sch")
		(duplicate_pad_numbers_are_jumpers no)
		(pad "1" smd rect
			(at -0.7 0 90)
			(size 1.1 1.05)
			(layers "F.Cu" "F.Mask" "F.Paste")
			(net "GND")
		)
		(pad "2" smd rect
			(at 0.7 0 90)
			(size 1.1 1.05)
			(layers "F.Cu" "F.Mask" "F.Paste")
			(net "+5.0V")
		)
	)
	(footprint "Vault:FP-MK212BG-MFG"
		(layer "F.Cu")
		(at 85.8761 79.0786 -90)
		(property "Reference" "C60"
			(at 1.5 -4.593345 90)
			(unlocked yes)
			(layer "F.SilkS")
			(effects
				(font
					(size 0.762 0.762)
					(thickness 0.2286)
				)
				(justify left bottom)
			)
		)
		(property "Value" "10uF"
			(at 3.52679 1.5875 0)
			(unlocked yes)
			(layer "F.SilkS")
			(hide yes)
			(effects
				(font
					(size 1.524 1.524)
					(thickness 0.254)
				)
				(justify left bottom)
			)
		)
		(sheetname "GPS_IMU_SENSORS")
		(sheetfile "GPS_IMU_SENSORS.kicad_sch")
		(duplicate_pad_numbers_are_jumpers no)
		(fp_line
			(start 0.125 0.725)
			(end -0.125 0.725)
			(stroke
				(width 0.2)
				(type solid)
			)
			(layer "F.SilkS")
		)
		(fp_line
			(start 0.125 -0.725)
			(end -0.125 -0.725)
			(stroke
				(width 0.2)
				(type solid)
			)
			(layer "F.SilkS")
		)
		(fp_line
			(start -1.6 0.825)
			(end -1.6 -0.825)
			(stroke
				(width 0.2)
				(type solid)
			)
			(layer "F.CrtYd")
		)
		(fp_line
			(start 1.6 0.825)
			(end -1.6 0.825)
			(stroke
				(width 0.2)
				(type solid)
			)
			(layer "F.CrtYd")
		)
		(fp_line
			(start 1.6 0.825)
			(end 1.6 -0.825)
			(stroke
				(width 0.2)
				(type solid)
			)
			(layer "F.CrtYd")
		)
		(fp_line
			(start 1.6 -0.825)
			(end -1.6 -0.825)
			(stroke
				(width 0.2)
				(type solid)
			)
			(layer "F.CrtYd")
		)
		(fp_line
			(start -1.6 0.825)
			(end -1.6 -0.825)
			(stroke
				(width 0.2)
				(type solid)
			)
			(layer "F.Fab")
		)
		(fp_line
			(start 1.6 0.825)
			(end -1.6 0.825)
			(stroke
				(width 0.2)
				(type solid)
			)
			(layer "F.Fab")
		)
		(fp_line
			(start 1.6 0.825)
			(end 1.6 -0.825)
			(stroke
				(width 0.2)
				(type solid)
			)
			(layer "F.Fab")
		)
		(fp_line
			(start 0 0.5)
			(end 0 -0.5)
			(stroke
				(width 0.1)
				(type solid)
			)
			(layer "F.Fab")
		)
		(fp_line
			(start 0.5 0)
			(end -0.5 0)
			(stroke
				(width 0.1)
				(type solid)
			)
			(layer "F.Fab")
		)
		(fp_line
			(start 1.6 -0.825)
			(end -1.6 -0.825)
			(stroke
				(width 0.2)
				(type solid)
			)
			(layer "F.Fab")
		)
		(fp_text user "${REFERENCE}"
			(at -0.00001 0.09601 270)
			(unlocked yes)
			(layer "F.Fab")
			(effects
				(font
					(face "Arial")
					(size 0.63 0.63)
					(thickness 0.1)
				)
				(justify left bottom)
			)
		)
		(pad "1" smd rect
			(at -1 0 270)
			(size 1 1.25)
			(layers "F.Cu" "F.Mask" "F.Paste")
			(net "+5.0V")
			(solder_mask_margin 0)
			(solder_paste_margin 0)
		)
		(pad "2" smd rect
			(at 1 0 270)
			(size 1 1.25)
			(layers "F.Cu" "F.Mask" "F.Paste")
			(net "GND")
			(solder_mask_margin 0)
			(solder_paste_margin 0)
		)
	)
)
